(kicad_pcb
	(version 20241229)
	(generator "pcbnew")
	(generator_version "9.0")
	(general
		(thickness 1.294)
		(legacy_teardrops no)
	)
	(paper "A3")
	(title_block
		(title "Kintex 410T devboard")
		(date "2024-04-03")
		(rev "1.1.2")
		(comment 9 "footprints 96-101 of 975")
	)
	(layers
		(0 "F.Cu" mixed)
		(4 "In1.Cu" power)
		(6 "In2.Cu" power)
		(8 "In3.Cu" mixed)
		(10 "In4.Cu" power)
		(12 "In5.Cu" mixed)
		(14 "In6.Cu" power)
		(16 "In7.Cu" mixed)
		(18 "In8.Cu" power)
		(2 "B.Cu" mixed)
		(9 "F.Adhes" user "F.Adhesive")
		(11 "B.Adhes" user "B.Adhesive")
		(13 "F.Paste" user)
		(15 "B.Paste" user)
		(5 "F.SilkS" user "F.Silkscreen")
		(7 "B.SilkS" user "B.Silkscreen")
		(1 "F.Mask" user)
		(3 "B.Mask" user)
		(17 "Dwgs.User" user "User.Drawings")
		(19 "Cmts.User" user "User.Comments")
		(21 "Eco1.User" user "User.Eco1")
		(23 "Eco2.User" user "User.Eco2")
		(25 "Edge.Cuts" user)
		(27 "Margin" user)
		(31 "F.CrtYd" user "F.Courtyard")
		(29 "B.CrtYd" user "B.Courtyard")
		(35 "F.Fab" user)
		(33 "B.Fab" user)
	)
	(footprint "antmicro-footprints:TP_SMD_0.75mm"
		(layer "F.Cu")
		(at 156.4625 176.675)
		(property "Reference" "TP4"
			(at 0.3375 2.475 90)
			(layer "F.SilkS")
			(effects
				(font
					(size 0.7 0.7)
					(thickness 0.15)
				)
				(justify left bottom)
			)
		)
		(property "Value" "TP_0.75mm_SMD"
			(at 0 1.2 0)
			(layer "F.Fab")
			(effects
				(font
					(size 0.7 0.7)
					(thickness 0.15)
				)
				(justify left bottom)
			)
		)
		(property "Description" "SMT test point"
			(at 0 0 0)
			(layer "F.Fab")
			(hide yes)
			(effects
				(font
					(size 1.27 1.27)
					(thickness 0.15)
				)
			)
		)
		(property "Author" "Antmicro"
			(at 0 0 0)
			(layer "F.Fab")
			(hide yes)
			(effects
				(font
					(size 1 1)
					(thickness 0.15)
				)
			)
		)
		(property "License" "Apache-2.0"
			(at 0 0 0)
			(layer "F.Fab")
			(hide yes)
			(effects
				(font
					(size 1 1)
					(thickness 0.15)
				)
			)
		)
		(property "MPN" ""
			(at 0 0 0)
			(layer "F.Fab")
			(hide yes)
			(effects
				(font
					(size 1 1)
					(thickness 0.15)
				)
			)
		)
		(property "Manufacturer" ""
			(at 0 0 0)
			(layer "F.Fab")
			(hide yes)
			(effects
				(font
					(size 1 1)
					(thickness 0.15)
				)
			)
		)
		(sheetname "DC-DC Converters")
		(sheetfile "dc-dc.kicad_sch")
		(attr exclude_from_pos_files)
		(pad "1" smd circle
			(at 0 0)
			(size 0.75 0.75)
			(layers "F.Cu" "F.Mask")
			(net 1413 "/SUP_MCU.PG_1V2")
			(pinfunction "1")
			(pintype "passive")
		)
	)
	(footprint "antmicro-footprints:C_0402_1005Metric"
		(layer "F.Cu")
		(at 228.725 140.75 -90)
		(descr "Capacitor SMD 0402")
		(tags "capacitor SMD 0402")
		(property "Reference" "C368"
			(at 3.15 0.125 0)
			(layer "F.SilkS")
			(effects
				(font
					(size 0.7 0.7)
					(thickness 0.15)
				)
				(justify right bottom)
			)
		)
		(property "Value" "C_100n_0402"
			(at 0 1.4 90)
			(layer "F.Fab")
			(effects
				(font
					(size 0.7 0.7)
					(thickness 0.15)
				)
				(justify right bottom)
			)
		)
		(property "Description" "SMD Multilayer Ceramic Capacitor, 0.1 µF, 50 V, 0402 [1005 Metric], ± 10%, X5R, GRM Series"
			(at 0 0 270)
			(layer "F.Fab")
			(hide yes)
			(effects
				(font
					(size 1.27 1.27)
					(thickness 0.15)
				)
			)
		)
		(property "Author" "Antmicro"
			(at 87.975 369.475 0)
			(layer "F.Fab")
			(hide yes)
			(effects
				(font
					(size 1 1)
					(thickness 0.15)
				)
			)
		)
		(property "Dielectric" "X5R"
			(at 87.975 369.475 0)
			(layer "F.Fab")
			(hide yes)
			(effects
				(font
					(size 1 1)
					(thickness 0.15)
				)
			)
		)
		(property "License" "Apache-2.0"
			(at 87.975 369.475 0)
			(layer "F.Fab")
			(hide yes)
			(effects
				(font
					(size 1 1)
					(thickness 0.15)
				)
			)
		)
		(property "MPN" "GRM155R61H104KE14D"
			(at 87.975 369.475 0)
			(layer "F.Fab")
			(hide yes)
			(effects
				(font
					(size 1 1)
					(thickness 0.15)
				)
			)
		)
		(property "Manufacturer" "Murata"
			(at 87.975 369.475 0)
			(layer "F.Fab")
			(hide yes)
			(effects
				(font
					(size 1 1)
					(thickness 0.15)
				)
			)
		)
		(property "Val" "100n"
			(at 87.975 369.475 0)
			(layer "F.Fab")
			(hide yes)
			(effects
				(font
					(size 1 1)
					(thickness 0.15)
				)
			)
		)
		(property "Voltage" "50V"
			(at 87.975 369.475 0)
			(layer "F.Fab")
			(hide yes)
			(effects
				(font
					(size 1 1)
					(thickness 0.15)
				)
			)
		)
		(sheetname "Clocks")
		(sheetfile "clocks.kicad_sch")
		(attr smd)
		(fp_rect
			(start -0.925 -0.47)
			(end 0.925 0.47)
			(stroke
				(width 0.05)
				(type default)
			)
			(fill no)
			(layer "F.CrtYd")
		)
		(fp_line
			(start -0.494 0.248)
			(end -0.494 -0.25)
			(stroke
				(width 0.15)
				(type solid)
			)
			(layer "F.Fab")
		)
		(fp_line
			(start 0.504 0.248)
			(end -0.494 0.248)
			(stroke
				(width 0.15)
				(type solid)
			)
			(layer "F.Fab")
		)
		(fp_line
			(start -0.494 -0.25)
			(end 0.504 -0.25)
			(stroke
				(width 0.15)
				(type solid)
			)
			(layer "F.Fab")
		)
		(fp_line
			(start 0.504 -0.25)
			(end 0.504 0.248)
			(stroke
				(width 0.15)
				(type solid)
			)
			(layer "F.Fab")
		)
		(pad "1" smd roundrect
			(at -0.48 0 270)
			(size 0.59 0.64)
			(layers "F.Cu" "F.Mask" "F.Paste")
			(roundrect_rratio 0.25)
			(net 1 "GND")
			(pintype "passive")
		)
		(pad "2" smd roundrect
			(at 0.48 0 270)
			(size 0.59 0.64)
			(layers "F.Cu" "F.Mask" "F.Paste")
			(roundrect_rratio 0.25)
			(net 1231 "Net-(C366-Pad2)")
			(pintype "passive")
		)
	)
	(footprint "antmicro-footprints:R_0402_1005Metric"
		(layer "F.Cu")
		(at 218.4 147.8)
		(descr "Resistor SMD 0402")
		(tags "resistor SMD 0402")
		(property "Reference" "R198"
			(at -3.6 0.35 180)
			(layer "F.SilkS")
			(effects
				(font
					(size 0.7 0.7)
					(thickness 0.15)
				)
				(justify left bottom)
			)
		)
		(property "Value" "R_1k_0402"
			(at 0 1.4 0)
			(layer "F.Fab")
			(effects
				(font
					(size 0.7 0.7)
					(thickness 0.15)
				)
				(justify left bottom)
			)
		)
		(property "Description" "SMD Chip Resistor, 1 kohm, ± 1%, 63 mW, 0402 [1005 Metric], Thick Film, General Purpose"
			(at 0 0 0)
			(layer "F.Fab")
			(hide yes)
			(effects
				(font
					(size 1.27 1.27)
					(thickness 0.15)
				)
			)
		)
		(property "Author" "Antmicro"
			(at 0 0 0)
			(layer "F.Fab")
			(hide yes)
			(effects
				(font
					(size 1 1)
					(thickness 0.15)
				)
			)
		)
		(property "License" "Apache-2.0"
			(at 0 0 0)
			(layer "F.Fab")
			(hide yes)
			(effects
				(font
					(size 1 1)
					(thickness 0.15)
				)
			)
		)
		(property "MPN" "CR0402-FX-1001GLF"
			(at 0 0 0)
			(layer "F.Fab")
			(hide yes)
			(effects
				(font
					(size 1 1)
					(thickness 0.15)
				)
			)
		)
		(property "Manufacturer" "Bourns"
			(at 0 0 0)
			(layer "F.Fab")
			(hide yes)
			(effects
				(font
					(size 1 1)
					(thickness 0.15)
				)
			)
		)
		(property "Tolerance" "1%"
			(at 0 0 0)
			(layer "F.Fab")
			(hide yes)
			(effects
				(font
					(size 1 1)
					(thickness 0.15)
				)
			)
		)
		(property "Val" "1k"
			(at 0 0 0)
			(layer "F.Fab")
			(hide yes)
			(effects
				(font
					(size 1 1)
					(thickness 0.15)
				)
			)
		)
		(sheetname "HDMI + Ethernet")
		(sheetfile "hdmi-ethernet.kicad_sch")
		(attr smd)
		(fp_rect
			(start -0.925 -0.47)
			(end 0.925 0.47)
			(stroke
				(width 0.05)
				(type default)
			)
			(fill no)
			(layer "F.CrtYd")
		)
		(fp_rect
			(start -0.5 -0.25)
			(end 0.5 0.25)
			(stroke
				(width 0.15)
				(type solid)
			)
			(fill no)
			(layer "F.Fab")
		)
		(pad "1" smd roundrect
			(at -0.48 0)
			(size 0.59 0.64)
			(layers "F.Cu" "F.Mask" "F.Paste")
			(roundrect_rratio 0.25)
			(net 26 "+1V8")
			(pintype "passive")
		)
		(pad "2" smd roundrect
			(at 0.48 0)
			(size 0.59 0.64)
			(layers "F.Cu" "F.Mask" "F.Paste")
			(roundrect_rratio 0.25)
			(net 502 "/FPGA Bank 18 & 32/ETH_RMII.MDIO")
			(pintype "passive")
		)
	)
	(footprint "antmicro-footprints:C_0603_1608Metric"
		(layer "F.Cu")
		(at 195.6 158.349001)
		(descr "Capacitor SMD 0603")
		(tags "capacitor 0603")
		(property "Reference" "C359"
			(at -3.9 0.400999 0)
			(layer "F.SilkS")
			(effects
				(font
					(size 0.7 0.7)
					(thickness 0.15)
				)
				(justify left bottom)
			)
		)
		(property "Value" "C_22u_0603"
			(at 0 1.6 0)
			(layer "F.Fab")
			(effects
				(font
					(size 0.7 0.7)
					(thickness 0.15)
				)
				(justify left bottom)
			)
		)
		(property "Description" "SMD Multilayer Ceramic Capacitor, 22 µF, 6.3 V, 0603 [1608 Metric], ± 20%, X5R, GRM Series"
			(at 0 0 0)
			(layer "F.Fab")
			(hide yes)
			(effects
				(font
					(size 1.27 1.27)
					(thickness 0.15)
				)
			)
		)
		(property "Author" "Antmicro"
			(at 0 0 0)
			(layer "F.Fab")
			(hide yes)
			(effects
				(font
					(size 1 1)
					(thickness 0.15)
				)
			)
		)
		(property "Dielectric" ""
			(at 0 0 0)
			(layer "F.Fab")
			(hide yes)
			(effects
				(font
					(size 1 1)
					(thickness 0.15)
				)
			)
		)
		(property "License" "Apache-2.0"
			(at 0 0 0)
			(layer "F.Fab")
			(hide yes)
			(effects
				(font
					(size 1 1)
					(thickness 0.15)
				)
			)
		)
		(property "MPN" "GRM188R60J226MEA0D"
			(at 0 0 0)
			(layer "F.Fab")
			(hide yes)
			(effects
				(font
					(size 1 1)
					(thickness 0.15)
				)
			)
		)
		(property "Manufacturer" "Murata"
			(at 0 0 0)
			(layer "F.Fab")
			(hide yes)
			(effects
				(font
					(size 1 1)
					(thickness 0.15)
				)
			)
		)
		(property "Val" "22u"
			(at 0 0 0)
			(layer "F.Fab")
			(hide yes)
			(effects
				(font
					(size 1 1)
					(thickness 0.15)
				)
			)
		)
		(property "Voltage" ""
			(at 0 0 0)
			(layer "F.Fab")
			(hide yes)
			(effects
				(font
					(size 1 1)
					(thickness 0.15)
				)
			)
		)
		(sheetname "DC-DC Converters")
		(sheetfile "dc-dc.kicad_sch")
		(attr smd)
		(fp_line
			(start -0.15 -0.4)
			(end 0.15 -0.4)
			(stroke
				(width 0.15)
				(type solid)
			)
			(layer "F.SilkS")
		)
		(fp_line
			(start -0.15 0.4)
			(end 0.15 0.4)
			(stroke
				(width 0.15)
				(type solid)
			)
			(layer "F.SilkS")
		)
		(fp_rect
			(start -1.25 -0.65)
			(end 1.25 0.65)
			(stroke
				(width 0.05)
				(type solid)
			)
			(fill no)
			(layer "F.CrtYd")
		)
		(fp_rect
			(start -0.8 -0.4)
			(end 0.8 0.4)
			(stroke
				(width 0.15)
				(type solid)
			)
			(fill no)
			(layer "F.Fab")
		)
		(pad "1" smd roundrect
			(at -0.7 0)
			(size 0.8 1)
			(layers "F.Cu" "F.Mask" "F.Paste")
			(roundrect_rratio 0.2)
			(net 1 "GND")
			(pintype "passive")
		)
		(pad "2" smd roundrect
			(at 0.7 0)
			(size 0.8 1)
			(layers "F.Cu" "F.Mask" "F.Paste")
			(roundrect_rratio 0.2)
			(net 751 "/DC-DC Converters/1V0_REG")
			(pintype "passive")
		)
	)
	(footprint "antmicro-footprints:SOD-523"
		(layer "F.Cu")
		(at 236.4 137.7 180)
		(property "Reference" "D30"
			(at 3.1 -0.35 180)
			(layer "F.SilkS")
			(effects
				(font
					(size 0.7 0.7)
					(thickness 0.15)
				)
				(justify left bottom)
			)
		)
		(property "Value" "BAT54-02V-G3-08"
			(at 0 1.499 180)
			(layer "F.Fab")
			(effects
				(font
					(size 0.7 0.7)
					(thickness 0.15)
				)
				(justify left bottom)
			)
		)
		(property "Description" "Small Signal Schottky Diode, Single, 30 V, 200 mA, 800 mV, 600 mA, 125 °C"
			(at 0 0 180)
			(layer "F.Fab")
			(hide yes)
			(effects
				(font
					(size 1.27 1.27)
					(thickness 0.15)
				)
			)
		)
		(property "Author" "Antmicro"
			(at 472.8 275.4 0)
			(layer "F.Fab")
			(hide yes)
			(effects
				(font
					(size 1 1)
					(thickness 0.15)
				)
			)
		)
		(property "License" "Apache-2.0"
			(at 472.8 275.4 0)
			(layer "F.Fab")
			(hide yes)
			(effects
				(font
					(size 1 1)
					(thickness 0.15)
				)
			)
		)
		(property "MPN" "BAT54-02V-G3-08"
			(at 472.8 275.4 0)
			(layer "F.Fab")
			(hide yes)
			(effects
				(font
					(size 1 1)
					(thickness 0.15)
				)
			)
		)
		(property "Manufacturer" "Vishay"
			(at 472.8 275.4 0)
			(layer "F.Fab")
			(hide yes)
			(effects
				(font
					(size 1 1)
					(thickness 0.15)
				)
			)
		)
		(property "Public" "False"
			(at 472.8 275.4 0)
			(layer "F.Fab")
			(hide yes)
			(effects
				(font
					(size 1 1)
					(thickness 0.15)
				)
			)
		)
		(sheetname "USB PHY")
		(sheetfile "usb-phy.kicad_sch")
		(attr smd)
		(fp_line
			(start -0.35 -0.5)
			(end -0.35 0.5)
			(stroke
				(width 0.15)
				(type solid)
			)
			(layer "F.SilkS")
		)
		(fp_rect
			(start -1 -0.6)
			(end 1 0.6)
			(stroke
				(width 0.05)
				(type solid)
			)
			(fill no)
			(layer "F.CrtYd")
		)
		(fp_line
			(start 0.65 -0.425)
			(end 0.65 0.423)
			(stroke
				(width 0.15)
				(type solid)
			)
			(layer "F.Fab")
		)
		(fp_line
			(start -0.35 -0.4)
			(end -0.35 0.4)
			(stroke
				(width 0.15)
				(type solid)
			)
			(layer "F.Fab")
		)
		(fp_line
			(start -0.652 0.423)
			(end 0.65 0.423)
			(stroke
				(width 0.15)
				(type solid)
			)
			(layer "F.Fab")
		)
		(fp_line
			(start -0.652 0.423)
			(end -0.652 -0.425)
			(stroke
				(width 0.15)
				(type solid)
			)
			(layer "F.Fab")
		)
		(fp_line
			(start -0.652 -0.425)
			(end 0.65 -0.425)
			(stroke
				(width 0.15)
				(type solid)
			)
			(layer "F.Fab")
		)
		(pad "1" smd roundrect
			(at -0.701 0 180)
			(size 0.5 0.6)
			(layers "F.Cu" "F.Mask" "F.Paste")
			(roundrect_rratio 0.25)
			(net 1047 "/USB PHY/FTDI_SDA_OUT")
			(pinfunction "C")
			(pintype "passive")
		)
		(pad "2" smd roundrect
			(at 0.699 0 180)
			(size 0.5 0.6)
			(layers "F.Cu" "F.Mask" "F.Paste")
			(roundrect_rratio 0.25)
			(net 942 "/USB PHY/FTDI_SDA_IN")
			(pinfunction "A")
			(pintype "passive")
		)
	)
	(footprint "antmicro-footprints:C_0402_1005Metric"
		(layer "F.Cu")
		(at 159.8 155.7 -90)
		(descr "Capacitor SMD 0402")
		(tags "capacitor SMD 0402")
		(property "Reference" "C344"
			(at 0.75 -0.4 90)
			(layer "F.SilkS")
			(effects
				(font
					(size 0.7 0.7)
					(thickness 0.15)
				)
				(justify right bottom)
			)
		)
		(property "Value" "C_10u_0402"
			(at 0 1.4 90)
			(layer "F.Fab")
			(effects
				(font
					(size 0.7 0.7)
					(thickness 0.15)
				)
				(justify right bottom)
			)
		)
		(property "Description" "SMD Multilayer Ceramic Capacitor, 10 µF, 6.3 V, 0402 [1005 Metric], ± 20%, X5R, CC Series"
			(at 0 0 270)
			(layer "F.Fab")
			(hide yes)
			(effects
				(font
					(size 1.27 1.27)
					(thickness 0.15)
				)
			)
		)
		(property "Author" "Antmicro"
			(at 4.1 315.5 0)
			(layer "F.Fab")
			(hide yes)
			(effects
				(font
					(size 1 1)
					(thickness 0.15)
				)
			)
		)
		(property "Dielectric" ""
			(at 4.1 315.5 0)
			(layer "F.Fab")
			(hide yes)
			(effects
				(font
					(size 1 1)
					(thickness 0.15)
				)
			)
		)
		(property "License" "Apache-2.0"
			(at 4.1 315.5 0)
			(layer "F.Fab")
			(hide yes)
			(effects
				(font
					(size 1 1)
					(thickness 0.15)
				)
			)
		)
		(property "MPN" "CC0402MRX5R5BB106"
			(at 4.1 315.5 0)
			(layer "F.Fab")
			(hide yes)
			(effects
				(font
					(size 1 1)
					(thickness 0.15)
				)
			)
		)
		(property "Manufacturer" "YAGEO"
			(at 4.1 315.5 0)
			(layer "F.Fab")
			(hide yes)
			(effects
				(font
					(size 1 1)
					(thickness 0.15)
				)
			)
		)
		(property "Val" "10u"
			(at 4.1 315.5 0)
			(layer "F.Fab")
			(hide yes)
			(effects
				(font
					(size 1 1)
					(thickness 0.15)
				)
			)
		)
		(property "Voltage" ""
			(at 4.1 315.5 0)
			(layer "F.Fab")
			(hide yes)
			(effects
				(font
					(size 1 1)
					(thickness 0.15)
				)
			)
		)
		(sheetname "DC-DC Converters")
		(sheetfile "dc-dc.kicad_sch")
		(attr smd)
		(fp_rect
			(start -0.925 -0.47)
			(end 0.925 0.47)
			(stroke
				(width 0.05)
				(type default)
			)
			(fill no)
			(layer "F.CrtYd")
		)
		(fp_line
			(start -0.494 0.248)
			(end -0.494 -0.25)
			(stroke
				(width 0.15)
				(type solid)
			)
			(layer "F.Fab")
		)
		(fp_line
			(start 0.504 0.248)
			(end -0.494 0.248)
			(stroke
				(width 0.15)
				(type solid)
			)
			(layer "F.Fab")
		)
		(fp_line
			(start -0.494 -0.25)
			(end 0.504 -0.25)
			(stroke
				(width 0.15)
				(type solid)
			)
			(layer "F.Fab")
		)
		(fp_line
			(start 0.504 -0.25)
			(end 0.504 0.248)
			(stroke
				(width 0.15)
				(type solid)
			)
			(layer "F.Fab")
		)
		(pad "1" smd roundrect
			(at -0.48 0 270)
			(size 0.59 0.64)
			(layers "F.Cu" "F.Mask" "F.Paste")
			(roundrect_rratio 0.25)
			(net 1 "GND")
			(pintype "passive")
		)
		(pad "2" smd roundrect
			(at 0.48 0 270)
			(size 0.59 0.64)
			(layers "F.Cu" "F.Mask" "F.Paste")
			(roundrect_rratio 0.25)
			(net 25 "+1V35")
			(pintype "passive")
		)
	)
)
